# T6G (Grand Teton) — schematic netlist excerpt (pin names and nets, part order shuffled) for the footprints in the layout excerpt that follows; sources: Cadence DE-HDL packaged netlist, KiCad conversion of 04192023_DAF0TMB3IC0_F0TG_MB_C_brd_V02_OCP.brd

PC427_5  Q_CAP  22UF 16V 20% X6S  pkg C0805  page 220 : A = SW_P12V_AUX_PVDDCR_CPU1_P1_FLT ; B = GND
PC417_3  Q_CAP  22UF 4V 20% X6S  pkg C0805  page 219 : A = PVDDCR_CPU1_P1 ; B = GND
R518  Q_RES  2.2K 5% CHIP  pkg 0402LF  page 54 : A = PVDD18_S5_P1 ; B = CPU1_SA0

(kicad_pcb
	(version 20260206)
	(generator "pcbnew")
	(generator_version "10.0")
	(general
		(thickness 1.6)
		(legacy_teardrops no)
	)
	(paper "A4")
	(title_block
		(title "04192023_DAF0TMB3IC0_F0TG_MB_C_brd_V02_OCP.brd")
		(comment 1 "Grand Teton / footprints 7509-7511 of 8354")
	)
	(layers
		(0 "F.Cu" signal "TOP")
		(4 "In1.Cu" signal "GND")
		(6 "In2.Cu" signal "IN1")
		(8 "In3.Cu" signal "GND1")
		(10 "In4.Cu" signal "IN2")
		(12 "In5.Cu" signal "GND2")
		(14 "In6.Cu" signal "IN3")
		(16 "In7.Cu" signal "GND3")
		(18 "In8.Cu" signal "VCC")
		(20 "In9.Cu" signal "VCC1")
		(22 "In10.Cu" signal "GND4")
		(24 "In11.Cu" signal "IN4")
		(26 "In12.Cu" signal "GND5")
		(28 "In13.Cu" signal "IN5")
		(30 "In14.Cu" signal "GND6")
		(32 "In15.Cu" signal "IN6")
		(34 "In16.Cu" signal "GND7")
		(2 "B.Cu" signal "BOTTOM")
		(9 "F.Adhes" user "F.Adhesive")
		(11 "B.Adhes" user "B.Adhesive")
		(13 "F.Paste" user "Package Geometry/Pastemask Top")
		(15 "B.Paste" user "Package Geometry/Pastemask Bottom")
		(5 "F.SilkS" user "Ref Des/Silkscreen Top")
		(7 "B.SilkS" user "Ref Des/Silkscreen Bottom")
		(1 "F.Mask" user "Board Geometry/Soldermask Top")
		(3 "B.Mask" user "Board Geometry/Soldermask Bottom")
		(17 "Dwgs.User" user "User.Drawings")
		(19 "Cmts.User" user "User.Comments")
		(21 "Eco1.User" user "User.Eco1")
		(23 "Eco2.User" user "User.Eco2")
		(25 "Edge.Cuts" user "Board Geometry/Outline")
		(27 "Margin" user)
		(31 "F.CrtYd" user "Package Geometry/Place Bound Top")
		(29 "B.CrtYd" user "Package Geometry/Place Bound Bottom")
		(35 "F.Fab" user "Ref Des/Assembly Top")
		(33 "B.Fab" user "Ref Des/Assembly Bottom")
	)
	(footprint ""
		(layer "B.Cu")
		(at 91.271852 -304.325274)
		(property "Reference" "R518"
			(at 0 0 0)
			(layer "B.SilkS")
			(hide yes)
			(effects
				(font
					(size 1.27 1.27)
				)
				(justify mirror)
			)
		)
		(property "Value" ""
			(at 0 0 0)
			(layer "B.Fab")
			(effects
				(font
					(size 1.27 1.27)
				)
				(justify mirror)
			)
		)
		(duplicate_pad_numbers_are_jumpers no)
		(fp_line
			(start -0.7874 -0.4064)
			(end -0.7874 0.4064)
			(stroke
				(width 0.1524)
				(type default)
			)
			(layer "B.SilkS")
		)
		(fp_line
			(start -0.7874 0.4064)
			(end 0.7874 0.4064)
			(stroke
				(width 0.1524)
				(type default)
			)
			(layer "B.SilkS")
		)
		(fp_line
			(start 0.7874 -0.4064)
			(end -0.7874 -0.4064)
			(stroke
				(width 0.1524)
				(type default)
			)
			(layer "B.SilkS")
		)
		(fp_line
			(start 0.7874 0.4064)
			(end 0.7874 -0.4064)
			(stroke
				(width 0.1524)
				(type default)
			)
			(layer "B.SilkS")
		)
		(fp_line
			(start -0.67945 -0.3048)
			(end -0.67945 0.3048)
			(stroke
				(width 0.1)
				(type default)
			)
			(layer "B.Fab")
		)
		(fp_line
			(start -0.67945 0.3048)
			(end -0.120396 0.3048)
			(stroke
				(width 0.1)
				(type default)
			)
			(layer "B.Fab")
		)
		(fp_line
			(start -0.12065 -0.3048)
			(end -0.67945 -0.3048)
			(stroke
				(width 0.1)
				(type default)
			)
			(layer "B.Fab")
		)
		(fp_line
			(start -0.12065 -0.2794)
			(end -0.12065 -0.3048)
			(stroke
				(width 0.1)
				(type default)
			)
			(layer "B.Fab")
		)
		(fp_line
			(start -0.120396 0.2794)
			(end 0.12065 0.2794)
			(stroke
				(width 0.1)
				(type default)
			)
			(layer "B.Fab")
		)
		(fp_line
			(start -0.120396 0.3048)
			(end -0.120396 0.2794)
			(stroke
				(width 0.1)
				(type default)
			)
			(layer "B.Fab")
		)
		(fp_line
			(start 0.12065 -0.305054)
			(end 0.12065 -0.2794)
			(stroke
				(width 0.1)
				(type default)
			)
			(layer "B.Fab")
		)
		(fp_line
			(start 0.12065 -0.2794)
			(end -0.12065 -0.2794)
			(stroke
				(width 0.1)
				(type default)
			)
			(layer "B.Fab")
		)
		(fp_line
			(start 0.12065 0.2794)
			(end 0.12065 0.3048)
			(stroke
				(width 0.1)
				(type default)
			)
			(layer "B.Fab")
		)
		(fp_line
			(start 0.12065 0.3048)
			(end 0.67945 0.3048)
			(stroke
				(width 0.1)
				(type default)
			)
			(layer "B.Fab")
		)
		(fp_line
			(start 0.67945 -0.305054)
			(end 0.12065 -0.305054)
			(stroke
				(width 0.1)
				(type default)
			)
			(layer "B.Fab")
		)
		(fp_line
			(start 0.67945 0.3048)
			(end 0.67945 -0.305054)
			(stroke
				(width 0.1)
				(type default)
			)
			(layer "B.Fab")
		)
		(pad "1" smd circle
			(at 0.40005 0 180)
			(size 0 0)
			(layers "B.Cu" "B.Mask" "B.Paste")
			(net "PVDD18_S5_P1")
		)
		(pad "2" smd circle
			(at -0.40005 0 180)
			(size 0 0)
			(layers "B.Cu" "B.Mask" "B.Paste")
			(net "CPU1_SA0")
		)
	)
	(footprint ""
		(layer "B.Cu")
		(at 60.679076 -338.086954 -90)
		(property "Reference" "PC417_3"
			(at 0 0 90)
			(layer "B.SilkS")
			(hide yes)
			(effects
				(font
					(size 1.27 1.27)
				)
				(justify mirror)
			)
		)
		(property "Value" ""
			(at 0 0 90)
			(layer "B.Fab")
			(effects
				(font
					(size 1.27 1.27)
				)
				(justify mirror)
			)
		)
		(duplicate_pad_numbers_are_jumpers no)
		(fp_line
			(start -1.524 0.762)
			(end 1.524 0.762)
			(stroke
				(width 0.1524)
				(type default)
			)
			(layer "B.SilkS")
		)
		(fp_line
			(start 1.524 0.762)
			(end 1.524 -0.762)
			(stroke
				(width 0.1524)
				(type default)
			)
			(layer "B.SilkS")
		)
		(fp_line
			(start -1.524 -0.762)
			(end -1.524 0.762)
			(stroke
				(width 0.1524)
				(type default)
			)
			(layer "B.SilkS")
		)
		(fp_line
			(start 1.524 -0.762)
			(end -1.524 -0.762)
			(stroke
				(width 0.1524)
				(type default)
			)
			(layer "B.SilkS")
		)
		(fp_line
			(start -1.1049 0.724916)
			(end -1.1049 -0.724916)
			(stroke
				(width 0.1)
				(type default)
			)
			(layer "B.Fab")
		)
		(fp_line
			(start 1.1049 0.724916)
			(end -1.1049 0.724916)
			(stroke
				(width 0.1)
				(type default)
			)
			(layer "B.Fab")
		)
		(fp_line
			(start -1.1049 -0.724916)
			(end 1.1049 -0.724916)
			(stroke
				(width 0.1)
				(type default)
			)
			(layer "B.Fab")
		)
		(fp_line
			(start 1.1049 -0.724916)
			(end 1.1049 0.724916)
			(stroke
				(width 0.1)
				(type default)
			)
			(layer "B.Fab")
		)
		(pad "1" smd rect
			(at 0.889 0 270)
			(size 1.016 1.27)
			(layers "B.Cu" "B.Mask" "B.Paste")
			(net "PVDDCR_CPU1_P1")
		)
		(pad "2" smd rect
			(at -0.889 0 270)
			(size 1.016 1.27)
			(layers "B.Cu" "B.Mask" "B.Paste")
			(net "GND")
		)
	)
	(footprint ""
		(layer "B.Cu")
		(at 96.575118 -335.09712 90)
		(property "Reference" "PC427_5"
			(at 0 0 90)
			(layer "B.SilkS")
			(hide yes)
			(effects
				(font
					(size 1.27 1.27)
				)
				(justify mirror)
			)
		)
		(property "Value" ""
			(at 0 0 90)
			(layer "B.Fab")
			(effects
				(font
					(size 1.27 1.27)
				)
				(justify mirror)
			)
		)
		(duplicate_pad_numbers_are_jumpers no)
		(fp_line
			(start 1.524 -0.762)
			(end -1.524 -0.762)
			(stroke
				(width 0.1524)
				(type default)
			)
			(layer "B.SilkS")
		)
		(fp_line
			(start -1.524 -0.762)
			(end -1.524 0.762)
			(stroke
				(width 0.1524)
				(type default)
			)
			(layer "B.SilkS")
		)
		(fp_line
			(start 1.524 0.762)
			(end 1.524 -0.762)
			(stroke
				(width 0.1524)
				(type default)
			)
			(layer "B.SilkS")
		)
		(fp_line
			(start -1.524 0.762)
			(end 1.524 0.762)
			(stroke
				(width 0.1524)
				(type default)
			)
			(layer "B.SilkS")
		)
		(fp_line
			(start 1.1049 -0.724916)
			(end 1.1049 0.724916)
			(stroke
				(width 0.1)
				(type default)
			)
			(layer "B.Fab")
		)
		(fp_line
			(start -1.1049 -0.724916)
			(end 1.1049 -0.724916)
			(stroke
				(width 0.1)
				(type default)
			)
			(layer "B.Fab")
		)
		(fp_line
			(start 1.1049 0.724916)
			(end -1.1049 0.724916)
			(stroke
				(width 0.1)
				(type default)
			)
			(layer "B.Fab")
		)
		(fp_line
			(start -1.1049 0.724916)
			(end -1.1049 -0.724916)
			(stroke
				(width 0.1)
				(type default)
			)
			(layer "B.Fab")
		)
		(pad "1" smd rect
			(at 0.889 0 90)
			(size 1.016 1.27)
			(layers "B.Cu" "B.Mask" "B.Paste")
			(net "SW_P12V_AUX_PVDDCR_CPU1_P1_FLT")
		)
		(pad "2" smd rect
			(at -0.889 0 90)
			(size 1.016 1.27)
			(layers "B.Cu" "B.Mask" "B.Paste")
			(net "GND")
		)
	)
)
